# S9S_MB_2U (Grand Teton) — schematic netlist excerpt (pin names and nets, part order shuffled) for the footprints in the layout excerpt that follows; sources: Cadence DE-HDL packaged netlist, KiCad conversion of 03242023_DA0F0TMBIJ0_F0T_Motherboard_J_brd_V01_OCP.brd

R2504  Q_RES  33.2 1% CHIP  pkg 0402LF  page 115 : A = PWRGD_FAIL_CPU1_EF_R1 ; B = PWRGD_FAIL_CPU1_EF_R
C1913  Q_CAP  0.01UF 50V 10% X7R  pkg C0402  page 217 : A = P3V3_AUX_FPGA_VCCIO5 ; B = GND

(kicad_pcb
	(version 20260206)
	(generator "pcbnew")
	(generator_version "10.0")
	(general
		(thickness 1.6)
		(legacy_teardrops no)
	)
	(paper "A4")
	(title_block
		(title "03242023_DA0F0TMBIJ0_F0T_Motherboard_J_brd_V01_OCP.brd")
		(comment 1 "Grand Teton / footprints 4866-4867 of 6105")
	)
	(layers
		(0 "F.Cu" signal "TOP")
		(4 "In1.Cu" signal "GND")
		(6 "In2.Cu" signal "IN1")
		(8 "In3.Cu" signal "GND1")
		(10 "In4.Cu" signal "IN2")
		(12 "In5.Cu" signal "GND2")
		(14 "In6.Cu" signal "IN3")
		(16 "In7.Cu" signal "GND3")
		(18 "In8.Cu" signal "VCC")
		(20 "In9.Cu" signal "VCC1")
		(22 "In10.Cu" signal "GND4")
		(24 "In11.Cu" signal "IN4")
		(26 "In12.Cu" signal "GND5")
		(28 "In13.Cu" signal "IN5")
		(30 "In14.Cu" signal "GND6")
		(32 "In15.Cu" signal "IN6")
		(34 "In16.Cu" signal "GND7")
		(2 "B.Cu" signal "BOTTOM")
		(9 "F.Adhes" user "F.Adhesive")
		(11 "B.Adhes" user "B.Adhesive")
		(13 "F.Paste" user "Package Geometry/Pastemask Top")
		(15 "B.Paste" user "Package Geometry/Pastemask Bottom")
		(5 "F.SilkS" user "Ref Des/Silkscreen Top")
		(7 "B.SilkS" user "Ref Des/Silkscreen Bottom")
		(1 "F.Mask" user "Board Geometry/Soldermask Top")
		(3 "B.Mask" user "Board Geometry/Soldermask Bottom")
		(17 "Dwgs.User" user "User.Drawings")
		(19 "Cmts.User" user "User.Comments")
		(21 "Eco1.User" user "User.Eco1")
		(23 "Eco2.User" user "User.Eco2")
		(25 "Edge.Cuts" user "Board Geometry/Outline")
		(27 "Margin" user)
		(31 "F.CrtYd" user "Package Geometry/Place Bound Top")
		(29 "B.CrtYd" user "Package Geometry/Place Bound Bottom")
		(35 "F.Fab" user "Ref Des/Assembly Top")
		(33 "B.Fab" user "Ref Des/Assembly Bottom")
	)
	(footprint ""
		(layer "B.Cu")
		(at 185.691526 -312.982864 90)
		(property "Reference" "R2504"
			(at 0 0 90)
			(layer "B.SilkS")
			(hide yes)
			(effects
				(font
					(size 1.27 1.27)
				)
				(justify mirror)
			)
		)
		(property "Value" ""
			(at 0 0 90)
			(layer "B.Fab")
			(effects
				(font
					(size 1.27 1.27)
				)
				(justify mirror)
			)
		)
		(duplicate_pad_numbers_are_jumpers no)
		(fp_line
			(start 0.7874 -0.4064)
			(end -0.7874 -0.4064)
			(stroke
				(width 0.1524)
				(type default)
			)
			(layer "B.SilkS")
		)
		(fp_line
			(start -0.7874 -0.4064)
			(end -0.7874 0.4064)
			(stroke
				(width 0.1524)
				(type default)
			)
			(layer "B.SilkS")
		)
		(fp_line
			(start 0.7874 0.4064)
			(end 0.7874 -0.4064)
			(stroke
				(width 0.1524)
				(type default)
			)
			(layer "B.SilkS")
		)
		(fp_line
			(start -0.7874 0.4064)
			(end 0.7874 0.4064)
			(stroke
				(width 0.1524)
				(type default)
			)
			(layer "B.SilkS")
		)
		(fp_line
			(start 0.67945 -0.305054)
			(end 0.12065 -0.305054)
			(stroke
				(width 0.1)
				(type default)
			)
			(layer "B.Fab")
		)
		(fp_line
			(start 0.12065 -0.305054)
			(end 0.12065 -0.2794)
			(stroke
				(width 0.1)
				(type default)
			)
			(layer "B.Fab")
		)
		(fp_line
			(start -0.12065 -0.3048)
			(end -0.67945 -0.3048)
			(stroke
				(width 0.1)
				(type default)
			)
			(layer "B.Fab")
		)
		(fp_line
			(start -0.67945 -0.3048)
			(end -0.67945 0.3048)
			(stroke
				(width 0.1)
				(type default)
			)
			(layer "B.Fab")
		)
		(fp_line
			(start 0.12065 -0.2794)
			(end -0.12065 -0.2794)
			(stroke
				(width 0.1)
				(type default)
			)
			(layer "B.Fab")
		)
		(fp_line
			(start -0.12065 -0.2794)
			(end -0.12065 -0.3048)
			(stroke
				(width 0.1)
				(type default)
			)
			(layer "B.Fab")
		)
		(fp_line
			(start 0.12065 0.2794)
			(end 0.12065 0.3048)
			(stroke
				(width 0.1)
				(type default)
			)
			(layer "B.Fab")
		)
		(fp_line
			(start -0.120396 0.2794)
			(end 0.12065 0.2794)
			(stroke
				(width 0.1)
				(type default)
			)
			(layer "B.Fab")
		)
		(fp_line
			(start 0.67945 0.3048)
			(end 0.67945 -0.305054)
			(stroke
				(width 0.1)
				(type default)
			)
			(layer "B.Fab")
		)
		(fp_line
			(start 0.12065 0.3048)
			(end 0.67945 0.3048)
			(stroke
				(width 0.1)
				(type default)
			)
			(layer "B.Fab")
		)
		(fp_line
			(start -0.120396 0.3048)
			(end -0.120396 0.2794)
			(stroke
				(width 0.1)
				(type default)
			)
			(layer "B.Fab")
		)
		(fp_line
			(start -0.67945 0.3048)
			(end -0.120396 0.3048)
			(stroke
				(width 0.1)
				(type default)
			)
			(layer "B.Fab")
		)
		(pad "1" smd circle
			(at 0.40005 0 270)
			(size 0 0)
			(layers "B.Cu" "B.Mask" "B.Paste")
			(net "PWRGD_FAIL_CPU1_EF_R1")
		)
		(pad "2" smd circle
			(at -0.40005 0 270)
			(size 0 0)
			(layers "B.Cu" "B.Mask" "B.Paste")
			(net "PWRGD_FAIL_CPU1_EF_R")
		)
	)
	(footprint ""
		(layer "B.Cu")
		(at 174.155608 -105.375456 90)
		(property "Reference" "C1913"
			(at 0 0 90)
			(layer "B.SilkS")
			(hide yes)
			(effects
				(font
					(size 1.27 1.27)
				)
				(justify mirror)
			)
		)
		(property "Value" ""
			(at 0 0 90)
			(layer "B.Fab")
			(effects
				(font
					(size 1.27 1.27)
				)
				(justify mirror)
			)
		)
		(duplicate_pad_numbers_are_jumpers no)
		(fp_line
			(start 0.69215 -0.2921)
			(end -0.69215 -0.2921)
			(stroke
				(width 0.1524)
				(type default)
			)
			(layer "B.SilkS")
		)
		(fp_line
			(start -0.69215 -0.2921)
			(end -0.69215 0.2921)
			(stroke
				(width 0.1524)
				(type default)
			)
			(layer "B.SilkS")
		)
		(fp_line
			(start 0.69215 0.2921)
			(end 0.69215 -0.2921)
			(stroke
				(width 0.1524)
				(type default)
			)
			(layer "B.SilkS")
		)
		(fp_line
			(start -0.69215 0.2921)
			(end 0.69215 0.2921)
			(stroke
				(width 0.1524)
				(type default)
			)
			(layer "B.SilkS")
		)
		(fp_line
			(start 0.51435 -0.2794)
			(end -0.51435 -0.2794)
			(stroke
				(width 0.1)
				(type default)
			)
			(layer "B.Fab")
		)
		(fp_line
			(start -0.51435 -0.2794)
			(end -0.51435 0.2794)
			(stroke
				(width 0.1)
				(type default)
			)
			(layer "B.Fab")
		)
		(fp_line
			(start 0.51435 0.2794)
			(end 0.51435 -0.2794)
			(stroke
				(width 0.1)
				(type default)
			)
			(layer "B.Fab")
		)
		(fp_line
			(start -0.51435 0.2794)
			(end 0.51435 0.2794)
			(stroke
				(width 0.1)
				(type default)
			)
			(layer "B.Fab")
		)
		(pad "1" smd circle
			(at 0.40005 0 270)
			(size 0 0)
			(layers "B.Cu" "B.Mask" "B.Paste")
			(net "P3V3_AUX_FPGA_VCCIO5")
		)
		(pad "2" smd circle
			(at -0.40005 0 270)
			(size 0 0)
			(layers "B.Cu" "B.Mask" "B.Paste")
			(net "GND")
		)
		(zone
			(layer "B.Cu")
			(hatch none 0.5)
			(connect_pads
				(clearance 0)
			)
			(min_thickness 0.25)
			(keepout
				(tracks not_allowed)
				(vias allowed)
				(pads allowed)
				(copperpour not_allowed)
				(footprints allowed)
			)
			(placement
				(enabled no)
				(sheetname "")
			)
			(fill
				(thermal_gap 0.5)
				(thermal_bridge_width 0.5)
				(island_removal_mode 0)
			)
			(polygon
				(pts
					(xy 174.243238 -105.565956) (xy 174.301404 -105.474516) (xy 174.301404 -105.275126) (xy 174.243238 -105.184956)
					(xy 174.067978 -105.184956) (xy 174.009558 -105.275126) (xy 174.009558 -105.474516) (xy 174.067724 -105.565956)
				)
			)
		)
	)
)
